(kicad_pcb
	(version 20260206)
	(generator "pcbnew")
	(generator_version "10.0")
	(general
		(thickness 1.6)
		(legacy_teardrops no)
	)
	(paper "A4")
	(title_block
		(title "01162023_DA0F0TEBIF0_F0T_Expander_BD_F_brd_V02_OCP.brd")
		(comment 1 "Grand Teton / footprints 2547-2553 of 9728")
	)
	(layers
		(0 "F.Cu" signal "TOP")
		(4 "In1.Cu" signal "GND")
		(6 "In2.Cu" signal "VCC")
		(8 "In3.Cu" signal "VCC1")
		(10 "In4.Cu" signal "GND1")
		(12 "In5.Cu" signal "IN1")
		(14 "In6.Cu" signal "GND2")
		(16 "In7.Cu" signal "IN2")
		(18 "In8.Cu" signal "GND3")
		(20 "In9.Cu" signal "IN3")
		(22 "In10.Cu" signal "GND4")
		(24 "In11.Cu" signal "IN4")
		(26 "In12.Cu" signal "GND5")
		(28 "In13.Cu" signal "IN5")
		(30 "In14.Cu" signal "GND6")
		(32 "In15.Cu" signal "IN6")
		(34 "In16.Cu" signal "GND7")
		(2 "B.Cu" signal "BOTTOM")
		(9 "F.Adhes" user "F.Adhesive")
		(11 "B.Adhes" user "B.Adhesive")
		(13 "F.Paste" user "Package Geometry/Pastemask Top")
		(15 "B.Paste" user "Package Geometry/Pastemask Bottom")
		(5 "F.SilkS" user "Ref Des/Silkscreen Top")
		(7 "B.SilkS" user "Ref Des/Silkscreen Bottom")
		(1 "F.Mask" user "Board Geometry/Soldermask Top")
		(3 "B.Mask" user "Board Geometry/Soldermask Bottom")
		(17 "Dwgs.User" user "User.Drawings")
		(19 "Cmts.User" user "User.Comments")
		(21 "Eco1.User" user "User.Eco1")
		(23 "Eco2.User" user "User.Eco2")
		(25 "Edge.Cuts" user "Board Geometry/Outline")
		(27 "Margin" user)
		(31 "F.CrtYd" user "Package Geometry/Place Bound Top")
		(29 "B.CrtYd" user "Package Geometry/Place Bound Bottom")
		(35 "F.Fab" user "Ref Des/Assembly Top")
		(33 "B.Fab" user "Ref Des/Assembly Bottom")
	)
	(footprint ""
		(layer "F.Cu")
		(at 363.474 -215.011)
		(property "Reference" "R4610"
			(at 0 0 0)
			(layer "F.SilkS")
			(hide yes)
			(effects
				(font
					(size 1.27 1.27)
				)
			)
		)
		(property "Value" ""
			(at 0 0 0)
			(layer "F.Fab")
			(effects
				(font
					(size 1.27 1.27)
				)
			)
		)
		(duplicate_pad_numbers_are_jumpers no)
		(fp_line
			(start -0.7874 -0.4064)
			(end 0.7874 -0.4064)
			(stroke
				(width 0.1524)
				(type default)
			)
			(layer "F.SilkS")
		)
		(fp_line
			(start -0.7874 0.4064)
			(end -0.7874 -0.4064)
			(stroke
				(width 0.1524)
				(type default)
			)
			(layer "F.SilkS")
		)
		(fp_line
			(start 0.7874 -0.4064)
			(end 0.7874 0.4064)
			(stroke
				(width 0.1524)
				(type default)
			)
			(layer "F.SilkS")
		)
		(fp_line
			(start 0.7874 0.4064)
			(end -0.7874 0.4064)
			(stroke
				(width 0.1524)
				(type default)
			)
			(layer "F.SilkS")
		)
		(fp_line
			(start -0.67945 -0.305054)
			(end -0.12065 -0.305054)
			(stroke
				(width 0.1)
				(type default)
			)
			(layer "F.Fab")
		)
		(fp_line
			(start -0.67945 0.3048)
			(end -0.67945 -0.305054)
			(stroke
				(width 0.1)
				(type default)
			)
			(layer "F.Fab")
		)
		(fp_line
			(start -0.12065 -0.305054)
			(end -0.12065 -0.2794)
			(stroke
				(width 0.1)
				(type default)
			)
			(layer "F.Fab")
		)
		(fp_line
			(start -0.12065 -0.2794)
			(end 0.12065 -0.2794)
			(stroke
				(width 0.1)
				(type default)
			)
			(layer "F.Fab")
		)
		(fp_line
			(start -0.12065 0.2794)
			(end -0.12065 0.3048)
			(stroke
				(width 0.1)
				(type default)
			)
			(layer "F.Fab")
		)
		(fp_line
			(start -0.12065 0.3048)
			(end -0.67945 0.3048)
			(stroke
				(width 0.1)
				(type default)
			)
			(layer "F.Fab")
		)
		(fp_line
			(start 0.120396 0.2794)
			(end -0.12065 0.2794)
			(stroke
				(width 0.1)
				(type default)
			)
			(layer "F.Fab")
		)
		(fp_line
			(start 0.120396 0.3048)
			(end 0.120396 0.2794)
			(stroke
				(width 0.1)
				(type default)
			)
			(layer "F.Fab")
		)
		(fp_line
			(start 0.12065 -0.3048)
			(end 0.67945 -0.3048)
			(stroke
				(width 0.1)
				(type default)
			)
			(layer "F.Fab")
		)
		(fp_line
			(start 0.12065 -0.2794)
			(end 0.12065 -0.3048)
			(stroke
				(width 0.1)
				(type default)
			)
			(layer "F.Fab")
		)
		(fp_line
			(start 0.67945 -0.3048)
			(end 0.67945 0.3048)
			(stroke
				(width 0.1)
				(type default)
			)
			(layer "F.Fab")
		)
		(fp_line
			(start 0.67945 0.3048)
			(end 0.120396 0.3048)
			(stroke
				(width 0.1)
				(type default)
			)
			(layer "F.Fab")
		)
		(pad "1" smd circle
			(at -0.40005 0)
			(size 0 0)
			(layers "F.Cu" "F.Mask" "F.Paste")
			(net "PEX0_PCA9555_INT_N")
		)
		(pad "2" smd circle
			(at 0.40005 0)
			(size 0 0)
			(layers "F.Cu" "F.Mask" "F.Paste")
			(net "PEX0_PCA9555_0_INT_N")
		)
	)
	(footprint ""
		(layer "F.Cu")
		(at 428.424594 -84.476336 180)
		(property "Reference" "U46"
			(at -2.767076 -0.503936 90)
			(unlocked yes)
			(layer "F.SilkS")
			(effects
				(font
					(size 0.7874 0.5842)
					(thickness 0.1524)
				)
				(justify left)
			)
		)
		(property "Value" ""
			(at 0 0 180)
			(layer "F.Fab")
			(effects
				(font
					(size 1.27 1.27)
				)
			)
		)
		(duplicate_pad_numbers_are_jumpers no)
		(fp_line
			(start 2.0574 1.651)
			(end -2.0574 1.651)
			(stroke
				(width 0.1524)
				(type default)
			)
			(layer "F.SilkS")
		)
		(fp_line
			(start 2.0574 -1.651)
			(end 2.0574 1.651)
			(stroke
				(width 0.1524)
				(type default)
			)
			(layer "F.SilkS")
		)
		(fp_line
			(start 0.381 -1.651)
			(end 2.0574 -1.651)
			(stroke
				(width 0.1524)
				(type default)
			)
			(layer "F.SilkS")
		)
		(fp_line
			(start 0 -1.016)
			(end 0.381 -1.651)
			(stroke
				(width 0.1524)
				(type default)
			)
			(layer "F.SilkS")
		)
		(fp_line
			(start -0.381 -1.651)
			(end 0 -1.016)
			(stroke
				(width 0.1524)
				(type default)
			)
			(layer "F.SilkS")
		)
		(fp_line
			(start -2.0574 1.651)
			(end -2.0574 -1.651)
			(stroke
				(width 0.1524)
				(type default)
			)
			(layer "F.SilkS")
		)
		(fp_line
			(start -2.0574 -1.651)
			(end -0.381 -1.651)
			(stroke
				(width 0.1524)
				(type default)
			)
			(layer "F.SilkS")
		)
		(fp_poly
			(pts
				(xy -2.71272 -0.719328) (xy -2.71272 -1.344168) (xy -2.159 -1.016)
			)
			(stroke
				(width 0)
				(type default)
			)
			(fill yes)
			(layer "F.SilkS")
		)
		(fp_line
			(start 1.599946 1.199896)
			(end 0.899922 1.199896)
			(stroke
				(width 0.1)
				(type default)
			)
			(layer "F.Fab")
		)
		(fp_line
			(start 1.599946 -1.199896)
			(end 1.599946 1.199896)
			(stroke
				(width 0.1)
				(type default)
			)
			(layer "F.Fab")
		)
		(fp_line
			(start 0.899922 1.549908)
			(end -0.899922 1.549908)
			(stroke
				(width 0.1)
				(type default)
			)
			(layer "F.Fab")
		)
		(fp_line
			(start 0.899922 1.199896)
			(end 0.899922 1.549908)
			(stroke
				(width 0.1)
				(type default)
			)
			(layer "F.Fab")
		)
		(fp_line
			(start 0.899922 -1.199896)
			(end 1.599946 -1.199896)
			(stroke
				(width 0.1)
				(type default)
			)
			(layer "F.Fab")
		)
		(fp_line
			(start 0.899922 -1.549908)
			(end 0.899922 -1.199896)
			(stroke
				(width 0.1)
				(type default)
			)
			(layer "F.Fab")
		)
		(fp_line
			(start -0.899922 1.549908)
			(end -0.899922 1.199896)
			(stroke
				(width 0.1)
				(type default)
			)
			(layer "F.Fab")
		)
		(fp_line
			(start -0.899922 1.199896)
			(end -1.599946 1.199896)
			(stroke
				(width 0.1)
				(type default)
			)
			(layer "F.Fab")
		)
		(fp_line
			(start -0.899922 -1.199896)
			(end -0.899922 -1.549908)
			(stroke
				(width 0.1)
				(type default)
			)
			(layer "F.Fab")
		)
		(fp_line
			(start -0.899922 -1.549908)
			(end 0.899922 -1.549908)
			(stroke
				(width 0.1)
				(type default)
			)
			(layer "F.Fab")
		)
		(fp_line
			(start -1.599946 1.199896)
			(end -1.599946 -1.199896)
			(stroke
				(width 0.1)
				(type default)
			)
			(layer "F.Fab")
		)
		(fp_line
			(start -1.599946 -1.199896)
			(end -0.899922 -1.199896)
			(stroke
				(width 0.1)
				(type default)
			)
			(layer "F.Fab")
		)
		(fp_poly
			(pts
				(xy -2.71272 -0.719328) (xy -2.71272 -1.344168) (xy -2.159 -1.016)
			)
			(stroke
				(width 0)
				(type default)
			)
			(fill yes)
			(layer "F.Fab")
		)
		(pad "1" smd rect
			(at -1.225042 -0.94996 90)
			(size 0.5588 1.3462)
			(layers "F.Cu" "F.Mask" "F.Paste")
			(net "HP_NIC7_PWRGD_R")
		)
		(pad "2" smd rect
			(at -1.225042 0 90)
			(size 0.5588 1.3462)
			(layers "F.Cu" "F.Mask" "F.Paste")
			(net "RST_NIC7_PERST_R_N")
		)
		(pad "3" smd rect
			(at -1.225042 0.94996 90)
			(size 0.5588 1.3462)
			(layers "F.Cu" "F.Mask" "F.Paste")
			(net "GND")
		)
		(pad "4" smd rect
			(at 1.225042 0.94996 90)
			(size 0.5588 1.3462)
			(layers "F.Cu" "F.Mask" "F.Paste")
			(net "RST_HP_NIC7_N")
		)
		(pad "5" smd rect
			(at 1.225042 -0.94996 90)
			(size 0.5588 1.3462)
			(layers "F.Cu" "F.Mask" "F.Paste")
			(net "P3V3_AUX")
		)
	)
	(footprint ""
		(layer "F.Cu")
		(at 213.467442 -244.016276 -90)
		(property "Reference" "R6161"
			(at 0 0 270)
			(layer "F.SilkS")
			(hide yes)
			(effects
				(font
					(size 1.27 1.27)
				)
			)
		)
		(property "Value" ""
			(at 0 0 270)
			(layer "F.Fab")
			(effects
				(font
					(size 1.27 1.27)
				)
			)
		)
		(duplicate_pad_numbers_are_jumpers no)
		(fp_line
			(start -0.7874 0.4064)
			(end -0.7874 -0.4064)
			(stroke
				(width 0.1524)
				(type default)
			)
			(layer "F.SilkS")
		)
		(fp_line
			(start 0.7874 0.4064)
			(end -0.7874 0.4064)
			(stroke
				(width 0.1524)
				(type default)
			)
			(layer "F.SilkS")
		)
		(fp_line
			(start -0.7874 -0.4064)
			(end 0.7874 -0.4064)
			(stroke
				(width 0.1524)
				(type default)
			)
			(layer "F.SilkS")
		)
		(fp_line
			(start 0.7874 -0.4064)
			(end 0.7874 0.4064)
			(stroke
				(width 0.1524)
				(type default)
			)
			(layer "F.SilkS")
		)
		(fp_line
			(start -0.67945 0.3048)
			(end -0.67945 -0.305054)
			(stroke
				(width 0.1)
				(type default)
			)
			(layer "F.Fab")
		)
		(fp_line
			(start -0.12065 0.3048)
			(end -0.67945 0.3048)
			(stroke
				(width 0.1)
				(type default)
			)
			(layer "F.Fab")
		)
		(fp_line
			(start 0.120396 0.3048)
			(end 0.120396 0.2794)
			(stroke
				(width 0.1)
				(type default)
			)
			(layer "F.Fab")
		)
		(fp_line
			(start 0.67945 0.3048)
			(end 0.120396 0.3048)
			(stroke
				(width 0.1)
				(type default)
			)
			(layer "F.Fab")
		)
		(fp_line
			(start -0.12065 0.2794)
			(end -0.12065 0.3048)
			(stroke
				(width 0.1)
				(type default)
			)
			(layer "F.Fab")
		)
		(fp_line
			(start 0.120396 0.2794)
			(end -0.12065 0.2794)
			(stroke
				(width 0.1)
				(type default)
			)
			(layer "F.Fab")
		)
		(fp_line
			(start -0.12065 -0.2794)
			(end 0.12065 -0.2794)
			(stroke
				(width 0.1)
				(type default)
			)
			(layer "F.Fab")
		)
		(fp_line
			(start 0.12065 -0.2794)
			(end 0.12065 -0.3048)
			(stroke
				(width 0.1)
				(type default)
			)
			(layer "F.Fab")
		)
		(fp_line
			(start 0.12065 -0.3048)
			(end 0.67945 -0.3048)
			(stroke
				(width 0.1)
				(type default)
			)
			(layer "F.Fab")
		)
		(fp_line
			(start 0.67945 -0.3048)
			(end 0.67945 0.3048)
			(stroke
				(width 0.1)
				(type default)
			)
			(layer "F.Fab")
		)
		(fp_line
			(start -0.67945 -0.305054)
			(end -0.12065 -0.305054)
			(stroke
				(width 0.1)
				(type default)
			)
			(layer "F.Fab")
		)
		(fp_line
			(start -0.12065 -0.305054)
			(end -0.12065 -0.2794)
			(stroke
				(width 0.1)
				(type default)
			)
			(layer "F.Fab")
		)
		(pad "1" smd circle
			(at -0.40005 0 270)
			(size 0 0)
			(layers "F.Cu" "F.Mask" "F.Paste")
			(net "PWRGD_P1V8_PEX_R")
		)
		(pad "2" smd circle
			(at 0.40005 0 270)
			(size 0 0)
			(layers "F.Cu" "F.Mask" "F.Paste")
			(net "PWRGD_P1V8_PEX_R1")
		)
	)
	(footprint ""
		(layer "F.Cu")
		(at 219.202 -205.74)
		(property "Reference" "R1510"
			(at 0 0 0)
			(layer "F.SilkS")
			(hide yes)
			(effects
				(font
					(size 1.27 1.27)
				)
			)
		)
		(property "Value" ""
			(at 0 0 0)
			(layer "F.Fab")
			(effects
				(font
					(size 1.27 1.27)
				)
			)
		)
		(duplicate_pad_numbers_are_jumpers no)
		(fp_line
			(start -0.7874 -0.4064)
			(end 0.7874 -0.4064)
			(stroke
				(width 0.1524)
				(type default)
			)
			(layer "F.SilkS")
		)
		(fp_line
			(start -0.7874 0.4064)
			(end -0.7874 -0.4064)
			(stroke
				(width 0.1524)
				(type default)
			)
			(layer "F.SilkS")
		)
		(fp_line
			(start 0.7874 -0.4064)
			(end 0.7874 0.4064)
			(stroke
				(width 0.1524)
				(type default)
			)
			(layer "F.SilkS")
		)
		(fp_line
			(start 0.7874 0.4064)
			(end -0.7874 0.4064)
			(stroke
				(width 0.1524)
				(type default)
			)
			(layer "F.SilkS")
		)
		(fp_line
			(start -0.67945 -0.305054)
			(end -0.12065 -0.305054)
			(stroke
				(width 0.1)
				(type default)
			)
			(layer "F.Fab")
		)
		(fp_line
			(start -0.67945 0.3048)
			(end -0.67945 -0.305054)
			(stroke
				(width 0.1)
				(type default)
			)
			(layer "F.Fab")
		)
		(fp_line
			(start -0.12065 -0.305054)
			(end -0.12065 -0.2794)
			(stroke
				(width 0.1)
				(type default)
			)
			(layer "F.Fab")
		)
		(fp_line
			(start -0.12065 -0.2794)
			(end 0.12065 -0.2794)
			(stroke
				(width 0.1)
				(type default)
			)
			(layer "F.Fab")
		)
		(fp_line
			(start -0.12065 0.2794)
			(end -0.12065 0.3048)
			(stroke
				(width 0.1)
				(type default)
			)
			(layer "F.Fab")
		)
		(fp_line
			(start -0.12065 0.3048)
			(end -0.67945 0.3048)
			(stroke
				(width 0.1)
				(type default)
			)
			(layer "F.Fab")
		)
		(fp_line
			(start 0.120396 0.2794)
			(end -0.12065 0.2794)
			(stroke
				(width 0.1)
				(type default)
			)
			(layer "F.Fab")
		)
		(fp_line
			(start 0.120396 0.3048)
			(end 0.120396 0.2794)
			(stroke
				(width 0.1)
				(type default)
			)
			(layer "F.Fab")
		)
		(fp_line
			(start 0.12065 -0.3048)
			(end 0.67945 -0.3048)
			(stroke
				(width 0.1)
				(type default)
			)
			(layer "F.Fab")
		)
		(fp_line
			(start 0.12065 -0.2794)
			(end 0.12065 -0.3048)
			(stroke
				(width 0.1)
				(type default)
			)
			(layer "F.Fab")
		)
		(fp_line
			(start 0.67945 -0.3048)
			(end 0.67945 0.3048)
			(stroke
				(width 0.1)
				(type default)
			)
			(layer "F.Fab")
		)
		(fp_line
			(start 0.67945 0.3048)
			(end 0.120396 0.3048)
			(stroke
				(width 0.1)
				(type default)
			)
			(layer "F.Fab")
		)
		(pad "1" smd circle
			(at -0.40005 0)
			(size 0 0)
			(layers "F.Cu" "F.Mask" "F.Paste")
			(net "SMB_NIC4_LS_EN")
		)
		(pad "2" smd circle
			(at 0.40005 0)
			(size 0 0)
			(layers "F.Cu" "F.Mask" "F.Paste")
			(net "P3V3_NIC4")
		)
	)
	(footprint ""
		(layer "F.Cu")
		(at 312.477404 -343.952322 90)
		(property "Reference" "C551"
			(at 0 0 90)
			(layer "F.SilkS")
			(hide yes)
			(effects
				(font
					(size 1.27 1.27)
				)
			)
		)
		(property "Value" ""
			(at 0 0 90)
			(layer "F.Fab")
			(effects
				(font
					(size 1.27 1.27)
				)
			)
		)
		(duplicate_pad_numbers_are_jumpers no)
		(fp_line
			(start 0.299974 -0.150114)
			(end 0.299974 0.150114)
			(stroke
				(width 0.1)
				(type default)
			)
			(layer "F.Fab")
		)
		(fp_line
			(start -0.299974 -0.150114)
			(end 0.299974 -0.150114)
			(stroke
				(width 0.1)
				(type default)
			)
			(layer "F.Fab")
		)
		(fp_line
			(start 0.299974 0.150114)
			(end -0.299974 0.150114)
			(stroke
				(width 0.1)
				(type default)
			)
			(layer "F.Fab")
		)
		(fp_line
			(start -0.299974 0.150114)
			(end -0.299974 -0.150114)
			(stroke
				(width 0.1)
				(type default)
			)
			(layer "F.Fab")
		)
		(pad "1" smd rect
			(at -0.2667 0 90)
			(size 0.3048 0.381)
			(layers "F.Cu" "F.Mask" "F.Paste")
			(net "P5E_PEX2_STN6_TX_DP<111>")
		)
		(pad "2" smd rect
			(at 0.2667 0 90)
			(size 0.3048 0.381)
			(layers "F.Cu" "F.Mask" "F.Paste")
			(net "P5E_PEX2_STN6_TX_C_DP<111>")
		)
	)
	(footprint ""
		(layer "F.Cu")
		(at 242.310412 -121.661428 180)
		(property "Reference" "C2878"
			(at 0 0 180)
			(layer "F.SilkS")
			(hide yes)
			(effects
				(font
					(size 1.27 1.27)
				)
			)
		)
		(property "Value" ""
			(at 0 0 180)
			(layer "F.Fab")
			(effects
				(font
					(size 1.27 1.27)
				)
			)
		)
		(duplicate_pad_numbers_are_jumpers no)
		(fp_line
			(start 0.7874 0.4064)
			(end -0.7874 0.4064)
			(stroke
				(width 0.1524)
				(type default)
			)
			(layer "F.SilkS")
		)
		(fp_line
			(start 0.7874 -0.4064)
			(end 0.7874 0.4064)
			(stroke
				(width 0.1524)
				(type default)
			)
			(layer "F.SilkS")
		)
		(fp_line
			(start -0.7874 0.4064)
			(end -0.7874 -0.4064)
			(stroke
				(width 0.1524)
				(type default)
			)
			(layer "F.SilkS")
		)
		(fp_line
			(start -0.7874 -0.4064)
			(end 0.7874 -0.4064)
			(stroke
				(width 0.1524)
				(type default)
			)
			(layer "F.SilkS")
		)
		(fp_line
			(start 0.67945 0.3048)
			(end 0.120396 0.3048)
			(stroke
				(width 0.1)
				(type default)
			)
			(layer "F.Fab")
		)
		(fp_line
			(start 0.67945 -0.3048)
			(end 0.67945 0.3048)
			(stroke
				(width 0.1)
				(type default)
			)
			(layer "F.Fab")
		)
		(fp_line
			(start 0.12065 -0.2794)
			(end 0.12065 -0.3048)
			(stroke
				(width 0.1)
				(type default)
			)
			(layer "F.Fab")
		)
		(fp_line
			(start 0.12065 -0.3048)
			(end 0.67945 -0.3048)
			(stroke
				(width 0.1)
				(type default)
			)
			(layer "F.Fab")
		)
		(fp_line
			(start 0.120396 0.3048)
			(end 0.120396 0.2794)
			(stroke
				(width 0.1)
				(type default)
			)
			(layer "F.Fab")
		)
		(fp_line
			(start 0.120396 0.2794)
			(end -0.12065 0.2794)
			(stroke
				(width 0.1)
				(type default)
			)
			(layer "F.Fab")
		)
		(fp_line
			(start -0.12065 0.3048)
			(end -0.67945 0.3048)
			(stroke
				(width 0.1)
				(type default)
			)
			(layer "F.Fab")
		)
		(fp_line
			(start -0.12065 0.2794)
			(end -0.12065 0.3048)
			(stroke
				(width 0.1)
				(type default)
			)
			(layer "F.Fab")
		)
		(fp_line
			(start -0.12065 -0.2794)
			(end 0.12065 -0.2794)
			(stroke
				(width 0.1)
				(type default)
			)
			(layer "F.Fab")
		)
		(fp_line
			(start -0.12065 -0.305054)
			(end -0.12065 -0.2794)
			(stroke
				(width 0.1)
				(type default)
			)
			(layer "F.Fab")
		)
		(fp_line
			(start -0.67945 0.3048)
			(end -0.67945 -0.305054)
			(stroke
				(width 0.1)
				(type default)
			)
			(layer "F.Fab")
		)
		(fp_line
			(start -0.67945 -0.305054)
			(end -0.12065 -0.305054)
			(stroke
				(width 0.1)
				(type default)
			)
			(layer "F.Fab")
		)
		(pad "1" smd circle
			(at -0.40005 0 180)
			(size 0 0)
			(layers "F.Cu" "F.Mask" "F.Paste")
			(net "HP_NIC4_EN")
		)
		(pad "2" smd circle
			(at 0.40005 0 180)
			(size 0 0)
			(layers "F.Cu" "F.Mask" "F.Paste")
			(net "GND")
		)
	)
	(footprint ""
		(layer "F.Cu")
		(at 29.548328 -350.098614 90)
		(property "Reference" "C2161"
			(at 0 0 90)
			(layer "F.SilkS")
			(hide yes)
			(effects
				(font
					(size 1.27 1.27)
				)
			)
		)
		(property "Value" ""
			(at 0 0 90)
			(layer "F.Fab")
			(effects
				(font
					(size 1.27 1.27)
				)
			)
		)
		(duplicate_pad_numbers_are_jumpers no)
		(fp_line
			(start 0.299974 -0.150114)
			(end 0.299974 0.150114)
			(stroke
				(width 0.1)
				(type default)
			)
			(layer "F.Fab")
		)
		(fp_line
			(start -0.299974 -0.150114)
			(end 0.299974 -0.150114)
			(stroke
				(width 0.1)
				(type default)
			)
			(layer "F.Fab")
		)
		(fp_line
			(start 0.299974 0.150114)
			(end -0.299974 0.150114)
			(stroke
				(width 0.1)
				(type default)
			)
			(layer "F.Fab")
		)
		(fp_line
			(start -0.299974 0.150114)
			(end -0.299974 -0.150114)
			(stroke
				(width 0.1)
				(type default)
			)
			(layer "F.Fab")
		)
		(pad "1" smd rect
			(at -0.2667 0 90)
			(size 0.3048 0.381)
			(layers "F.Cu" "F.Mask" "F.Paste")
			(net "P5E_PEX0_STN4_TX_DN<75>")
		)
		(pad "2" smd rect
			(at 0.2667 0 90)
			(size 0.3048 0.381)
			(layers "F.Cu" "F.Mask" "F.Paste")
			(net "P5E_PEX0_STN4_TX_C_DN<75>")
		)
	)
)
